# BASEBOARD_FAB2 (Tioga Pass) — schematic netlist excerpt (pin names and nets, part order shuffled) for the footprints in the layout excerpt that follows; sources: Cadence DE-HDL packaged netlist, KiCad conversion of Wiwynn_Tioga_Pass_MB.brd

R4E8  RES  10.0 1% CHIP  pkg 0402  page 201 : A = VSENSE_PVCCIN_CPU0_P ; B = VSENSE_PVCCIN_CPU0_AVSP
R7A20  RES  68.1K 1% EMPTY  pkg 0402  page 219 : A = VR_PVDDQ_DEF_PH1_OCSET ; B = GND
C7C4  CAP  15.0PF 50V 5% COG  pkg 0402LF  page 114 : A = XTAL_PCH_48M_IN ; B = GND

(kicad_pcb
	(version 20260206)
	(generator "pcbnew")
	(generator_version "10.0")
	(general
		(thickness 1.6)
		(legacy_teardrops no)
	)
	(paper "A4")
	(title_block
		(title "Wiwynn_Tioga_Pass_MB.brd")
		(comment 1 "Tioga Pass / footprints 1531-1533 of 4770")
	)
	(layers
		(0 "F.Cu" signal "TOP")
		(4 "In1.Cu" signal "L2GND")
		(6 "In2.Cu" signal "L3")
		(8 "In3.Cu" signal "L4GND")
		(10 "In4.Cu" signal "L5")
		(12 "In5.Cu" signal "L6GND")
		(14 "In6.Cu" signal "L7VCC")
		(16 "In7.Cu" signal "L8VCC")
		(18 "In8.Cu" signal "L9GND")
		(20 "In9.Cu" signal "L10")
		(22 "In10.Cu" signal "L11GND")
		(24 "In11.Cu" signal "L12")
		(26 "In12.Cu" signal "L13GND")
		(2 "B.Cu" signal "BOTTOM")
		(9 "F.Adhes" user "F.Adhesive")
		(11 "B.Adhes" user "B.Adhesive")
		(13 "F.Paste" user "Package Geometry/Pastemask Top")
		(15 "B.Paste" user "Package Geometry/Pastemask Bottom")
		(5 "F.SilkS" user "Ref Des/Silkscreen Top")
		(7 "B.SilkS" user "Ref Des/Silkscreen Bottom")
		(1 "F.Mask" user "Board Geometry/Soldermask Top")
		(3 "B.Mask" user "Board Geometry/Soldermask Bottom")
		(17 "Dwgs.User" user "User.Drawings")
		(19 "Cmts.User" user "User.Comments")
		(21 "Eco1.User" user "User.Eco1")
		(23 "Eco2.User" user "User.Eco2")
		(25 "Edge.Cuts" user "Board Geometry/Outline")
		(27 "Margin" user)
		(31 "F.CrtYd" user "Package Geometry/Place Bound Top")
		(29 "B.CrtYd" user "Package Geometry/Place Bound Bottom")
		(35 "F.Fab" user "Ref Des/Assembly Top")
		(33 "B.Fab" user "Ref Des/Assembly Bottom")
	)
	(footprint ""
		(layer "F.Cu")
		(at 368.69624 -107.893866 180)
		(property "Reference" "C7C4"
			(at 0 0 180)
			(layer "F.SilkS")
			(hide yes)
			(effects
				(font
					(size 1.27 1.27)
				)
			)
		)
		(property "Value" ""
			(at 0 0 180)
			(layer "F.Fab")
			(effects
				(font
					(size 1.27 1.27)
				)
			)
		)
		(duplicate_pad_numbers_are_jumpers no)
		(fp_poly
			(pts
				(xy 0.3048 -0.1016) (xy 0.3048 0.9906) (xy -0.3048 0.9906) (xy -0.3048 -0.1016)
			)
			(stroke
				(width 0)
				(type default)
			)
			(fill no)
			(layer "F.CrtYd")
		)
		(fp_line
			(start 0.3048 0.9906)
			(end 0.3048 -0.1016)
			(stroke
				(width 0.1)
				(type default)
			)
			(layer "F.Fab")
		)
		(fp_line
			(start 0.3048 -0.1016)
			(end -0.3048 -0.1016)
			(stroke
				(width 0.1)
				(type default)
			)
			(layer "F.Fab")
		)
		(fp_line
			(start -0.3048 0.9906)
			(end 0.3048 0.9906)
			(stroke
				(width 0.1)
				(type default)
			)
			(layer "F.Fab")
		)
		(fp_line
			(start -0.3048 -0.1016)
			(end -0.3048 0.9906)
			(stroke
				(width 0.1)
				(type default)
			)
			(layer "F.Fab")
		)
		(pad "1" smd rect
			(at 0 0 180)
			(size 0.508 0.508)
			(layers "F.Cu" "F.Mask" "F.Paste")
			(net "XTAL_PCH_48M_IN")
		)
		(pad "2" smd rect
			(at 0 0.889 180)
			(size 0.508 0.508)
			(layers "F.Cu" "F.Mask" "F.Paste")
			(net "GND")
		)
		(zone
			(layer "F.Cu")
			(hatch none 0.5)
			(connect_pads
				(clearance 0)
			)
			(min_thickness 0.25)
			(keepout
				(tracks not_allowed)
				(vias allowed)
				(pads allowed)
				(copperpour not_allowed)
				(footprints allowed)
			)
			(placement
				(enabled no)
				(sheetname "")
			)
			(fill
				(thermal_gap 0.5)
				(thermal_bridge_width 0.5)
				(island_removal_mode 0)
			)
			(polygon
				(pts
					(xy 368.95024 -108.528866) (xy 368.44224 -108.528866) (xy 368.44224 -108.147866) (xy 368.95024 -108.147866)
				)
			)
		)
		(zone
			(layer "F.Cu")
			(hatch none 0.5)
			(connect_pads
				(clearance 0)
			)
			(min_thickness 0.25)
			(keepout
				(tracks allowed)
				(vias not_allowed)
				(pads allowed)
				(copperpour not_allowed)
				(footprints allowed)
			)
			(placement
				(enabled no)
				(sheetname "")
			)
			(fill
				(thermal_gap 0.5)
				(thermal_bridge_width 0.5)
				(island_removal_mode 0)
			)
			(polygon
				(pts
					(xy 368.95024 -108.147866) (xy 368.44224 -108.147866) (xy 368.44224 -108.528866) (xy 368.95024 -108.528866)
				)
			)
		)
	)
	(footprint ""
		(layer "F.Cu")
		(at 351.9932 -154.686 180)
		(property "Reference" "R7A20"
			(at 0 0 180)
			(layer "F.SilkS")
			(hide yes)
			(effects
				(font
					(size 1.27 1.27)
				)
			)
		)
		(property "Value" ""
			(at 0 0 180)
			(layer "F.Fab")
			(effects
				(font
					(size 1.27 1.27)
				)
			)
		)
		(duplicate_pad_numbers_are_jumpers no)
		(fp_poly
			(pts
				(xy -0.2794 -0.1016) (xy 0.2794 -0.1016) (xy 0.2794 0.9906) (xy -0.2794 0.9906)
			)
			(stroke
				(width 0)
				(type default)
			)
			(fill no)
			(layer "F.CrtYd")
		)
		(fp_line
			(start 0.2794 0.9906)
			(end 0.2794 -0.1016)
			(stroke
				(width 0.1)
				(type default)
			)
			(layer "F.Fab")
		)
		(fp_line
			(start 0.2794 -0.1016)
			(end -0.2794 -0.1016)
			(stroke
				(width 0.1)
				(type default)
			)
			(layer "F.Fab")
		)
		(fp_line
			(start -0.2794 0.9906)
			(end 0.2794 0.9906)
			(stroke
				(width 0.1)
				(type default)
			)
			(layer "F.Fab")
		)
		(fp_line
			(start -0.2794 -0.1016)
			(end -0.2794 0.9906)
			(stroke
				(width 0.1)
				(type default)
			)
			(layer "F.Fab")
		)
		(pad "1" smd rect
			(at 0 0 180)
			(size 0.508 0.508)
			(layers "F.Cu" "F.Mask" "F.Paste")
			(net "VR_PVDDQ_DEF_PH1_OCSET")
		)
		(pad "2" smd rect
			(at 0 0.889 180)
			(size 0.508 0.508)
			(layers "F.Cu" "F.Mask" "F.Paste")
			(net "GND")
		)
		(zone
			(layer "F.Cu")
			(hatch none 0.5)
			(connect_pads
				(clearance 0)
			)
			(min_thickness 0.25)
			(keepout
				(tracks not_allowed)
				(vias allowed)
				(pads allowed)
				(copperpour not_allowed)
				(footprints allowed)
			)
			(placement
				(enabled no)
				(sheetname "")
			)
			(fill
				(thermal_gap 0.5)
				(thermal_bridge_width 0.5)
				(island_removal_mode 0)
			)
			(polygon
				(pts
					(xy 352.2472 -155.321) (xy 351.7392 -155.321) (xy 351.7392 -154.94) (xy 352.2472 -154.94)
				)
			)
		)
		(zone
			(layer "F.Cu")
			(hatch none 0.5)
			(connect_pads
				(clearance 0)
			)
			(min_thickness 0.25)
			(keepout
				(tracks allowed)
				(vias not_allowed)
				(pads allowed)
				(copperpour not_allowed)
				(footprints allowed)
			)
			(placement
				(enabled no)
				(sheetname "")
			)
			(fill
				(thermal_gap 0.5)
				(thermal_bridge_width 0.5)
				(island_removal_mode 0)
			)
			(polygon
				(pts
					(xy 352.2472 -154.94) (xy 351.7392 -154.94) (xy 351.7392 -155.321) (xy 352.2472 -155.321)
				)
			)
		)
	)
	(footprint ""
		(layer "F.Cu")
		(at 187.833 -63.627 -90)
		(property "Reference" "R4E8"
			(at 0 0 270)
			(layer "F.SilkS")
			(hide yes)
			(effects
				(font
					(size 1.27 1.27)
				)
			)
		)
		(property "Value" ""
			(at 0 0 270)
			(layer "F.Fab")
			(effects
				(font
					(size 1.27 1.27)
				)
			)
		)
		(duplicate_pad_numbers_are_jumpers no)
		(fp_poly
			(pts
				(xy -0.2794 -0.1016) (xy 0.2794 -0.1016) (xy 0.2794 0.9906) (xy -0.2794 0.9906)
			)
			(stroke
				(width 0)
				(type default)
			)
			(fill no)
			(layer "F.CrtYd")
		)
		(fp_line
			(start -0.2794 0.9906)
			(end 0.2794 0.9906)
			(stroke
				(width 0.1)
				(type default)
			)
			(layer "F.Fab")
		)
		(fp_line
			(start 0.2794 0.9906)
			(end 0.2794 -0.1016)
			(stroke
				(width 0.1)
				(type default)
			)
			(layer "F.Fab")
		)
		(fp_line
			(start -0.2794 -0.1016)
			(end -0.2794 0.9906)
			(stroke
				(width 0.1)
				(type default)
			)
			(layer "F.Fab")
		)
		(fp_line
			(start 0.2794 -0.1016)
			(end -0.2794 -0.1016)
			(stroke
				(width 0.1)
				(type default)
			)
			(layer "F.Fab")
		)
		(pad "1" smd rect
			(at 0 0 270)
			(size 0.508 0.508)
			(layers "F.Cu" "F.Mask" "F.Paste")
			(net "VSENSE_PVCCIN_CPU0_P")
		)
		(pad "2" smd rect
			(at 0 0.889 270)
			(size 0.508 0.508)
			(layers "F.Cu" "F.Mask" "F.Paste")
			(net "VSENSE_PVCCIN_CPU0_AVSP")
		)
		(zone
			(layer "F.Cu")
			(hatch none 0.5)
			(connect_pads
				(clearance 0)
			)
			(min_thickness 0.25)
			(keepout
				(tracks not_allowed)
				(vias allowed)
				(pads allowed)
				(copperpour not_allowed)
				(footprints allowed)
			)
			(placement
				(enabled no)
				(sheetname "")
			)
			(fill
				(thermal_gap 0.5)
				(thermal_bridge_width 0.5)
				(island_removal_mode 0)
			)
			(polygon
				(pts
					(xy 187.198 -63.881) (xy 187.198 -63.373) (xy 187.579 -63.373) (xy 187.579 -63.881)
				)
			)
		)
		(zone
			(layer "F.Cu")
			(hatch none 0.5)
			(connect_pads
				(clearance 0)
			)
			(min_thickness 0.25)
			(keepout
				(tracks allowed)
				(vias not_allowed)
				(pads allowed)
				(copperpour not_allowed)
				(footprints allowed)
			)
			(placement
				(enabled no)
				(sheetname "")
			)
			(fill
				(thermal_gap 0.5)
				(thermal_bridge_width 0.5)
				(island_removal_mode 0)
			)
			(polygon
				(pts
					(xy 187.579 -63.881) (xy 187.579 -63.373) (xy 187.198 -63.373) (xy 187.198 -63.881)
				)
			)
		)
	)
)
